(kicad_pcb
	(version 20260206)
	(generator "pcbnew")
	(generator_version "10.0")
	(general
		(thickness 1.6)
		(legacy_teardrops no)
	)
	(paper "A4")
	(title_block
		(title "04192023_DAF0TMB3IC0_F0TG_MB_C_brd_V02_OCP.brd")
		(comment 1 "Grand Teton / footprints 6546-6553 of 8354")
	)
	(layers
		(0 "F.Cu" signal "TOP")
		(4 "In1.Cu" signal "GND")
		(6 "In2.Cu" signal "IN1")
		(8 "In3.Cu" signal "GND1")
		(10 "In4.Cu" signal "IN2")
		(12 "In5.Cu" signal "GND2")
		(14 "In6.Cu" signal "IN3")
		(16 "In7.Cu" signal "GND3")
		(18 "In8.Cu" signal "VCC")
		(20 "In9.Cu" signal "VCC1")
		(22 "In10.Cu" signal "GND4")
		(24 "In11.Cu" signal "IN4")
		(26 "In12.Cu" signal "GND5")
		(28 "In13.Cu" signal "IN5")
		(30 "In14.Cu" signal "GND6")
		(32 "In15.Cu" signal "IN6")
		(34 "In16.Cu" signal "GND7")
		(2 "B.Cu" signal "BOTTOM")
		(9 "F.Adhes" user "F.Adhesive")
		(11 "B.Adhes" user "B.Adhesive")
		(13 "F.Paste" user "Package Geometry/Pastemask Top")
		(15 "B.Paste" user "Package Geometry/Pastemask Bottom")
		(5 "F.SilkS" user "Ref Des/Silkscreen Top")
		(7 "B.SilkS" user "Ref Des/Silkscreen Bottom")
		(1 "F.Mask" user "Board Geometry/Soldermask Top")
		(3 "B.Mask" user "Board Geometry/Soldermask Bottom")
		(17 "Dwgs.User" user "User.Drawings")
		(19 "Cmts.User" user "User.Comments")
		(21 "Eco1.User" user "User.Eco1")
		(23 "Eco2.User" user "User.Eco2")
		(25 "Edge.Cuts" user "Board Geometry/Outline")
		(27 "Margin" user)
		(31 "F.CrtYd" user "Package Geometry/Place Bound Top")
		(29 "B.CrtYd" user "Package Geometry/Place Bound Bottom")
		(35 "F.Fab" user "Ref Des/Assembly Top")
		(33 "B.Fab" user "Ref Des/Assembly Bottom")
	)
	(footprint ""
		(layer "B.Cu")
		(at 404.115778 -323.892672 180)
		(property "Reference" "R1593"
			(at 0 0 0)
			(layer "B.SilkS")
			(hide yes)
			(effects
				(font
					(size 1.27 1.27)
				)
				(justify mirror)
			)
		)
		(property "Value" ""
			(at 0 0 0)
			(layer "B.Fab")
			(effects
				(font
					(size 1.27 1.27)
				)
				(justify mirror)
			)
		)
		(duplicate_pad_numbers_are_jumpers no)
		(fp_line
			(start 0.7874 0.4064)
			(end 0.7874 -0.4064)
			(stroke
				(width 0.1524)
				(type default)
			)
			(layer "B.SilkS")
		)
		(fp_line
			(start 0.7874 -0.4064)
			(end -0.7874 -0.4064)
			(stroke
				(width 0.1524)
				(type default)
			)
			(layer "B.SilkS")
		)
		(fp_line
			(start -0.7874 0.4064)
			(end 0.7874 0.4064)
			(stroke
				(width 0.1524)
				(type default)
			)
			(layer "B.SilkS")
		)
		(fp_line
			(start -0.7874 -0.4064)
			(end -0.7874 0.4064)
			(stroke
				(width 0.1524)
				(type default)
			)
			(layer "B.SilkS")
		)
		(fp_line
			(start 0.67945 0.3048)
			(end 0.67945 -0.305054)
			(stroke
				(width 0.1)
				(type default)
			)
			(layer "B.Fab")
		)
		(fp_line
			(start 0.67945 -0.305054)
			(end 0.12065 -0.305054)
			(stroke
				(width 0.1)
				(type default)
			)
			(layer "B.Fab")
		)
		(fp_line
			(start 0.12065 0.3048)
			(end 0.67945 0.3048)
			(stroke
				(width 0.1)
				(type default)
			)
			(layer "B.Fab")
		)
		(fp_line
			(start 0.12065 0.2794)
			(end 0.12065 0.3048)
			(stroke
				(width 0.1)
				(type default)
			)
			(layer "B.Fab")
		)
		(fp_line
			(start 0.12065 -0.2794)
			(end -0.12065 -0.2794)
			(stroke
				(width 0.1)
				(type default)
			)
			(layer "B.Fab")
		)
		(fp_line
			(start 0.12065 -0.305054)
			(end 0.12065 -0.2794)
			(stroke
				(width 0.1)
				(type default)
			)
			(layer "B.Fab")
		)
		(fp_line
			(start -0.120396 0.3048)
			(end -0.120396 0.2794)
			(stroke
				(width 0.1)
				(type default)
			)
			(layer "B.Fab")
		)
		(fp_line
			(start -0.120396 0.2794)
			(end 0.12065 0.2794)
			(stroke
				(width 0.1)
				(type default)
			)
			(layer "B.Fab")
		)
		(fp_line
			(start -0.12065 -0.2794)
			(end -0.12065 -0.3048)
			(stroke
				(width 0.1)
				(type default)
			)
			(layer "B.Fab")
		)
		(fp_line
			(start -0.12065 -0.3048)
			(end -0.67945 -0.3048)
			(stroke
				(width 0.1)
				(type default)
			)
			(layer "B.Fab")
		)
		(fp_line
			(start -0.67945 0.3048)
			(end -0.120396 0.3048)
			(stroke
				(width 0.1)
				(type default)
			)
			(layer "B.Fab")
		)
		(fp_line
			(start -0.67945 -0.3048)
			(end -0.67945 0.3048)
			(stroke
				(width 0.1)
				(type default)
			)
			(layer "B.Fab")
		)
		(pad "1" smd rect
			(at 0.40005 0 180)
			(size 0.4572 0.508)
			(layers "B.Cu" "B.Mask" "B.Paste")
			(net "ESPI_CPU0_ALERT_P0_N")
		)
		(pad "2" smd rect
			(at -0.40005 0 180)
			(size 0.4572 0.508)
			(layers "B.Cu" "B.Mask" "B.Paste")
			(net "CPU0_ESPI0_ALERT_N")
		)
	)
	(footprint ""
		(layer "B.Cu")
		(at 239.903 -333.883)
		(property "Reference" "R1361"
			(at 0 0 0)
			(layer "B.SilkS")
			(hide yes)
			(effects
				(font
					(size 1.27 1.27)
				)
				(justify mirror)
			)
		)
		(property "Value" ""
			(at 0 0 0)
			(layer "B.Fab")
			(effects
				(font
					(size 1.27 1.27)
				)
				(justify mirror)
			)
		)
		(duplicate_pad_numbers_are_jumpers no)
		(fp_line
			(start -0.32512 -0.175006)
			(end -0.32512 0.175006)
			(stroke
				(width 0.1)
				(type default)
			)
			(layer "B.Fab")
		)
		(fp_line
			(start -0.32512 0.175006)
			(end 0.32512 0.175006)
			(stroke
				(width 0.1)
				(type default)
			)
			(layer "B.Fab")
		)
		(fp_line
			(start 0.32512 -0.175006)
			(end -0.32512 -0.175006)
			(stroke
				(width 0.1)
				(type default)
			)
			(layer "B.Fab")
		)
		(fp_line
			(start 0.32512 0.175006)
			(end 0.32512 -0.175006)
			(stroke
				(width 0.1)
				(type default)
			)
			(layer "B.Fab")
		)
		(pad "1" smd rect
			(at 0.2667 0 180)
			(size 0.3048 0.381)
			(layers "B.Cu" "B.Mask" "B.Paste")
			(net "P1V8_CPU1_RT_1D")
		)
		(pad "2" smd rect
			(at -0.2667 0)
			(size 0.3048 0.381)
			(layers "B.Cu" "B.Mask" "B.Paste")
			(net "SMB_RT_CPU1_P0_ROM_MUX_2D_R_SDA")
		)
	)
	(footprint ""
		(layer "B.Cu")
		(at 239.903 -339.598)
		(property "Reference" "R1402"
			(at 0 0 0)
			(layer "B.SilkS")
			(hide yes)
			(effects
				(font
					(size 1.27 1.27)
				)
				(justify mirror)
			)
		)
		(property "Value" ""
			(at 0 0 0)
			(layer "B.Fab")
			(effects
				(font
					(size 1.27 1.27)
				)
				(justify mirror)
			)
		)
		(duplicate_pad_numbers_are_jumpers no)
		(fp_line
			(start -0.32512 -0.175006)
			(end -0.32512 0.175006)
			(stroke
				(width 0.1)
				(type default)
			)
			(layer "B.Fab")
		)
		(fp_line
			(start -0.32512 0.175006)
			(end 0.32512 0.175006)
			(stroke
				(width 0.1)
				(type default)
			)
			(layer "B.Fab")
		)
		(fp_line
			(start 0.32512 -0.175006)
			(end -0.32512 -0.175006)
			(stroke
				(width 0.1)
				(type default)
			)
			(layer "B.Fab")
		)
		(fp_line
			(start 0.32512 0.175006)
			(end 0.32512 -0.175006)
			(stroke
				(width 0.1)
				(type default)
			)
			(layer "B.Fab")
		)
		(pad "1" smd rect
			(at 0.2667 0 180)
			(size 0.3048 0.381)
			(layers "B.Cu" "B.Mask" "B.Paste")
			(net "P1V8_CPU1_RT_1D")
		)
		(pad "2" smd rect
			(at -0.2667 0)
			(size 0.3048 0.381)
			(layers "B.Cu" "B.Mask" "B.Paste")
			(net "SMB_RT_CPU1_P3_ROM_MUX_2D_R_SCL")
		)
	)
	(footprint ""
		(layer "B.Cu")
		(at 228.4857 -324.349872 180)
		(property "Reference" "C1086"
			(at 0 0 0)
			(layer "B.SilkS")
			(hide yes)
			(effects
				(font
					(size 1.27 1.27)
				)
				(justify mirror)
			)
		)
		(property "Value" ""
			(at 0 0 0)
			(layer "B.Fab")
			(effects
				(font
					(size 1.27 1.27)
				)
				(justify mirror)
			)
		)
		(duplicate_pad_numbers_are_jumpers no)
		(fp_line
			(start 0.7874 0.4064)
			(end 0.7874 -0.4064)
			(stroke
				(width 0.1524)
				(type default)
			)
			(layer "B.SilkS")
		)
		(fp_line
			(start 0.7874 -0.4064)
			(end -0.7874 -0.4064)
			(stroke
				(width 0.1524)
				(type default)
			)
			(layer "B.SilkS")
		)
		(fp_line
			(start -0.7874 0.4064)
			(end 0.7874 0.4064)
			(stroke
				(width 0.1524)
				(type default)
			)
			(layer "B.SilkS")
		)
		(fp_line
			(start -0.7874 -0.4064)
			(end -0.7874 0.4064)
			(stroke
				(width 0.1524)
				(type default)
			)
			(layer "B.SilkS")
		)
		(fp_line
			(start 0.67945 0.3048)
			(end 0.67945 -0.305054)
			(stroke
				(width 0.1)
				(type default)
			)
			(layer "B.Fab")
		)
		(fp_line
			(start 0.67945 -0.305054)
			(end 0.12065 -0.305054)
			(stroke
				(width 0.1)
				(type default)
			)
			(layer "B.Fab")
		)
		(fp_line
			(start 0.12065 0.3048)
			(end 0.67945 0.3048)
			(stroke
				(width 0.1)
				(type default)
			)
			(layer "B.Fab")
		)
		(fp_line
			(start 0.12065 0.2794)
			(end 0.12065 0.3048)
			(stroke
				(width 0.1)
				(type default)
			)
			(layer "B.Fab")
		)
		(fp_line
			(start 0.12065 -0.2794)
			(end -0.12065 -0.2794)
			(stroke
				(width 0.1)
				(type default)
			)
			(layer "B.Fab")
		)
		(fp_line
			(start 0.12065 -0.305054)
			(end 0.12065 -0.2794)
			(stroke
				(width 0.1)
				(type default)
			)
			(layer "B.Fab")
		)
		(fp_line
			(start -0.120396 0.3048)
			(end -0.120396 0.2794)
			(stroke
				(width 0.1)
				(type default)
			)
			(layer "B.Fab")
		)
		(fp_line
			(start -0.120396 0.2794)
			(end 0.12065 0.2794)
			(stroke
				(width 0.1)
				(type default)
			)
			(layer "B.Fab")
		)
		(fp_line
			(start -0.12065 -0.2794)
			(end -0.12065 -0.3048)
			(stroke
				(width 0.1)
				(type default)
			)
			(layer "B.Fab")
		)
		(fp_line
			(start -0.12065 -0.3048)
			(end -0.67945 -0.3048)
			(stroke
				(width 0.1)
				(type default)
			)
			(layer "B.Fab")
		)
		(fp_line
			(start -0.67945 0.3048)
			(end -0.120396 0.3048)
			(stroke
				(width 0.1)
				(type default)
			)
			(layer "B.Fab")
		)
		(fp_line
			(start -0.67945 -0.3048)
			(end -0.67945 0.3048)
			(stroke
				(width 0.1)
				(type default)
			)
			(layer "B.Fab")
		)
		(pad "1" smd circle
			(at 0.40005 0)
			(size 0 0)
			(layers "B.Cu" "B.Mask" "B.Paste")
			(net "P1V2_AUX_ADC_TIC")
		)
		(pad "2" smd circle
			(at -0.40005 0)
			(size 0 0)
			(layers "B.Cu" "B.Mask" "B.Paste")
			(net "GND")
		)
	)
	(footprint ""
		(layer "B.Cu")
		(at 113.105946 -257.74523 180)
		(property "Reference" "C2264"
			(at 0 0 0)
			(layer "B.SilkS")
			(hide yes)
			(effects
				(font
					(size 1.27 1.27)
				)
				(justify mirror)
			)
		)
		(property "Value" ""
			(at 0 0 0)
			(layer "B.Fab")
			(effects
				(font
					(size 1.27 1.27)
				)
				(justify mirror)
			)
		)
		(duplicate_pad_numbers_are_jumpers no)
		(fp_line
			(start 0.7874 0.4064)
			(end 0.7874 -0.4064)
			(stroke
				(width 0.1524)
				(type default)
			)
			(layer "B.SilkS")
		)
		(fp_line
			(start 0.7874 -0.4064)
			(end -0.7874 -0.4064)
			(stroke
				(width 0.1524)
				(type default)
			)
			(layer "B.SilkS")
		)
		(fp_line
			(start -0.7874 0.4064)
			(end 0.7874 0.4064)
			(stroke
				(width 0.1524)
				(type default)
			)
			(layer "B.SilkS")
		)
		(fp_line
			(start -0.7874 -0.4064)
			(end -0.7874 0.4064)
			(stroke
				(width 0.1524)
				(type default)
			)
			(layer "B.SilkS")
		)
		(fp_line
			(start 0.67945 0.3048)
			(end 0.67945 -0.305054)
			(stroke
				(width 0.1)
				(type default)
			)
			(layer "B.Fab")
		)
		(fp_line
			(start 0.67945 -0.305054)
			(end 0.12065 -0.305054)
			(stroke
				(width 0.1)
				(type default)
			)
			(layer "B.Fab")
		)
		(fp_line
			(start 0.12065 0.3048)
			(end 0.67945 0.3048)
			(stroke
				(width 0.1)
				(type default)
			)
			(layer "B.Fab")
		)
		(fp_line
			(start 0.12065 0.2794)
			(end 0.12065 0.3048)
			(stroke
				(width 0.1)
				(type default)
			)
			(layer "B.Fab")
		)
		(fp_line
			(start 0.12065 -0.2794)
			(end -0.12065 -0.2794)
			(stroke
				(width 0.1)
				(type default)
			)
			(layer "B.Fab")
		)
		(fp_line
			(start 0.12065 -0.305054)
			(end 0.12065 -0.2794)
			(stroke
				(width 0.1)
				(type default)
			)
			(layer "B.Fab")
		)
		(fp_line
			(start -0.120396 0.3048)
			(end -0.120396 0.2794)
			(stroke
				(width 0.1)
				(type default)
			)
			(layer "B.Fab")
		)
		(fp_line
			(start -0.120396 0.2794)
			(end 0.12065 0.2794)
			(stroke
				(width 0.1)
				(type default)
			)
			(layer "B.Fab")
		)
		(fp_line
			(start -0.12065 -0.2794)
			(end -0.12065 -0.3048)
			(stroke
				(width 0.1)
				(type default)
			)
			(layer "B.Fab")
		)
		(fp_line
			(start -0.12065 -0.3048)
			(end -0.67945 -0.3048)
			(stroke
				(width 0.1)
				(type default)
			)
			(layer "B.Fab")
		)
		(fp_line
			(start -0.67945 0.3048)
			(end -0.120396 0.3048)
			(stroke
				(width 0.1)
				(type default)
			)
			(layer "B.Fab")
		)
		(fp_line
			(start -0.67945 -0.3048)
			(end -0.67945 0.3048)
			(stroke
				(width 0.1)
				(type default)
			)
			(layer "B.Fab")
		)
		(pad "1" smd circle
			(at 0.40005 0)
			(size 0 0)
			(layers "B.Cu" "B.Mask" "B.Paste")
			(net "PVDDCR_SOC_P1")
		)
		(pad "2" smd circle
			(at -0.40005 0)
			(size 0 0)
			(layers "B.Cu" "B.Mask" "B.Paste")
			(net "GND")
		)
	)
	(footprint ""
		(layer "B.Cu")
		(at 379.441202 -416.899344 90)
		(property "Reference" "C6601"
			(at 0 0 90)
			(layer "B.SilkS")
			(hide yes)
			(effects
				(font
					(size 1.27 1.27)
				)
				(justify mirror)
			)
		)
		(property "Value" ""
			(at 0 0 90)
			(layer "B.Fab")
			(effects
				(font
					(size 1.27 1.27)
				)
				(justify mirror)
			)
		)
		(duplicate_pad_numbers_are_jumpers no)
		(fp_line
			(start 0.299974 -0.150114)
			(end -0.299974 -0.150114)
			(stroke
				(width 0.1)
				(type default)
			)
			(layer "B.Fab")
		)
		(fp_line
			(start -0.299974 -0.150114)
			(end -0.299974 0.150114)
			(stroke
				(width 0.1)
				(type default)
			)
			(layer "B.Fab")
		)
		(fp_line
			(start 0.299974 0.150114)
			(end 0.299974 -0.150114)
			(stroke
				(width 0.1)
				(type default)
			)
			(layer "B.Fab")
		)
		(fp_line
			(start -0.299974 0.150114)
			(end 0.299974 0.150114)
			(stroke
				(width 0.1)
				(type default)
			)
			(layer "B.Fab")
		)
		(pad "1" smd rect
			(at 0.2667 0 270)
			(size 0.3048 0.381)
			(layers "B.Cu" "B.Mask" "B.Paste")
			(net "P5E_CPU0_P3_TX_BUF_C_DP<2>")
		)
		(pad "2" smd rect
			(at -0.2667 0 270)
			(size 0.3048 0.381)
			(layers "B.Cu" "B.Mask" "B.Paste")
			(net "P5E_CPU0_P3_TX_BUF_DP<2>")
		)
	)
	(footprint ""
		(layer "B.Cu")
		(at 304.590958 -398.942052 90)
		(property "Reference" "C565"
			(at 0 0 90)
			(layer "B.SilkS")
			(hide yes)
			(effects
				(font
					(size 1.27 1.27)
				)
				(justify mirror)
			)
		)
		(property "Value" ""
			(at 0 0 90)
			(layer "B.Fab")
			(effects
				(font
					(size 1.27 1.27)
				)
				(justify mirror)
			)
		)
		(duplicate_pad_numbers_are_jumpers no)
		(fp_line
			(start 0.7874 -0.4064)
			(end -0.7874 -0.4064)
			(stroke
				(width 0.1524)
				(type default)
			)
			(layer "B.SilkS")
		)
		(fp_line
			(start -0.7874 -0.4064)
			(end -0.7874 0.4064)
			(stroke
				(width 0.1524)
				(type default)
			)
			(layer "B.SilkS")
		)
		(fp_line
			(start 0.7874 0.4064)
			(end 0.7874 -0.4064)
			(stroke
				(width 0.1524)
				(type default)
			)
			(layer "B.SilkS")
		)
		(fp_line
			(start -0.7874 0.4064)
			(end 0.7874 0.4064)
			(stroke
				(width 0.1524)
				(type default)
			)
			(layer "B.SilkS")
		)
		(fp_line
			(start 0.67945 -0.305054)
			(end 0.12065 -0.305054)
			(stroke
				(width 0.1)
				(type default)
			)
			(layer "B.Fab")
		)
		(fp_line
			(start 0.12065 -0.305054)
			(end 0.12065 -0.2794)
			(stroke
				(width 0.1)
				(type default)
			)
			(layer "B.Fab")
		)
		(fp_line
			(start -0.12065 -0.3048)
			(end -0.67945 -0.3048)
			(stroke
				(width 0.1)
				(type default)
			)
			(layer "B.Fab")
		)
		(fp_line
			(start -0.67945 -0.3048)
			(end -0.67945 0.3048)
			(stroke
				(width 0.1)
				(type default)
			)
			(layer "B.Fab")
		)
		(fp_line
			(start 0.12065 -0.2794)
			(end -0.12065 -0.2794)
			(stroke
				(width 0.1)
				(type default)
			)
			(layer "B.Fab")
		)
		(fp_line
			(start -0.12065 -0.2794)
			(end -0.12065 -0.3048)
			(stroke
				(width 0.1)
				(type default)
			)
			(layer "B.Fab")
		)
		(fp_line
			(start 0.12065 0.2794)
			(end 0.12065 0.3048)
			(stroke
				(width 0.1)
				(type default)
			)
			(layer "B.Fab")
		)
		(fp_line
			(start -0.120396 0.2794)
			(end 0.12065 0.2794)
			(stroke
				(width 0.1)
				(type default)
			)
			(layer "B.Fab")
		)
		(fp_line
			(start 0.67945 0.3048)
			(end 0.67945 -0.305054)
			(stroke
				(width 0.1)
				(type default)
			)
			(layer "B.Fab")
		)
		(fp_line
			(start 0.12065 0.3048)
			(end 0.67945 0.3048)
			(stroke
				(width 0.1)
				(type default)
			)
			(layer "B.Fab")
		)
		(fp_line
			(start -0.120396 0.3048)
			(end -0.120396 0.2794)
			(stroke
				(width 0.1)
				(type default)
			)
			(layer "B.Fab")
		)
		(fp_line
			(start -0.67945 0.3048)
			(end -0.120396 0.3048)
			(stroke
				(width 0.1)
				(type default)
			)
			(layer "B.Fab")
		)
		(pad "1" smd circle
			(at 0.40005 0 270)
			(size 0 0)
			(layers "B.Cu" "B.Mask" "B.Paste")
			(net "P0V9_CPU0_RT0_2A")
		)
		(pad "2" smd circle
			(at -0.40005 0 270)
			(size 0 0)
			(layers "B.Cu" "B.Mask" "B.Paste")
			(net "GND")
		)
	)
	(footprint ""
		(layer "B.Cu")
		(at 268.892528 -195.859146 180)
		(property "Reference" "R1679"
			(at 0 0 0)
			(layer "B.SilkS")
			(hide yes)
			(effects
				(font
					(size 1.27 1.27)
				)
				(justify mirror)
			)
		)
		(property "Value" ""
			(at 0 0 0)
			(layer "B.Fab")
			(effects
				(font
					(size 1.27 1.27)
				)
				(justify mirror)
			)
		)
		(duplicate_pad_numbers_are_jumpers no)
		(fp_line
			(start 0.7874 0.4064)
			(end 0.7874 -0.4064)
			(stroke
				(width 0.1524)
				(type default)
			)
			(layer "B.SilkS")
		)
		(fp_line
			(start 0.7874 -0.4064)
			(end -0.7874 -0.4064)
			(stroke
				(width 0.1524)
				(type default)
			)
			(layer "B.SilkS")
		)
		(fp_line
			(start -0.7874 0.4064)
			(end 0.7874 0.4064)
			(stroke
				(width 0.1524)
				(type default)
			)
			(layer "B.SilkS")
		)
		(fp_line
			(start -0.7874 -0.4064)
			(end -0.7874 0.4064)
			(stroke
				(width 0.1524)
				(type default)
			)
			(layer "B.SilkS")
		)
		(fp_line
			(start 0.67945 0.3048)
			(end 0.67945 -0.305054)
			(stroke
				(width 0.1)
				(type default)
			)
			(layer "B.Fab")
		)
		(fp_line
			(start 0.67945 -0.305054)
			(end 0.12065 -0.305054)
			(stroke
				(width 0.1)
				(type default)
			)
			(layer "B.Fab")
		)
		(fp_line
			(start 0.12065 0.3048)
			(end 0.67945 0.3048)
			(stroke
				(width 0.1)
				(type default)
			)
			(layer "B.Fab")
		)
		(fp_line
			(start 0.12065 0.2794)
			(end 0.12065 0.3048)
			(stroke
				(width 0.1)
				(type default)
			)
			(layer "B.Fab")
		)
		(fp_line
			(start 0.12065 -0.2794)
			(end -0.12065 -0.2794)
			(stroke
				(width 0.1)
				(type default)
			)
			(layer "B.Fab")
		)
		(fp_line
			(start 0.12065 -0.305054)
			(end 0.12065 -0.2794)
			(stroke
				(width 0.1)
				(type default)
			)
			(layer "B.Fab")
		)
		(fp_line
			(start -0.120396 0.3048)
			(end -0.120396 0.2794)
			(stroke
				(width 0.1)
				(type default)
			)
			(layer "B.Fab")
		)
		(fp_line
			(start -0.120396 0.2794)
			(end 0.12065 0.2794)
			(stroke
				(width 0.1)
				(type default)
			)
			(layer "B.Fab")
		)
		(fp_line
			(start -0.12065 -0.2794)
			(end -0.12065 -0.3048)
			(stroke
				(width 0.1)
				(type default)
			)
			(layer "B.Fab")
		)
		(fp_line
			(start -0.12065 -0.3048)
			(end -0.67945 -0.3048)
			(stroke
				(width 0.1)
				(type default)
			)
			(layer "B.Fab")
		)
		(fp_line
			(start -0.67945 0.3048)
			(end -0.120396 0.3048)
			(stroke
				(width 0.1)
				(type default)
			)
			(layer "B.Fab")
		)
		(fp_line
			(start -0.67945 -0.3048)
			(end -0.67945 0.3048)
			(stroke
				(width 0.1)
				(type default)
			)
			(layer "B.Fab")
		)
		(pad "1" smd circle
			(at 0.40005 0)
			(size 0 0)
			(layers "B.Cu" "B.Mask" "B.Paste")
			(net "I3C_SPD_DDRAF_CPU0_SDA")
		)
		(pad "2" smd circle
			(at -0.40005 0)
			(size 0 0)
			(layers "B.Cu" "B.Mask" "B.Paste")
			(net "I3C_SPD_DDRF_CPU0_SDA")
		)
	)
)
